(kicad_pcb
	(version 20260206)
	(generator "pcbnew")
	(generator_version "10.0")
	(general
		(thickness 1.6)
		(legacy_teardrops no)
	)
	(paper "A4")
	(title_block
		(title "01162023_DA0F0TEBIF0_F0T_Expander_BD_F_brd_V02_OCP.brd")
		(comment 1 "Grand Teton / footprints 2052-2060 of 9728")
	)
	(layers
		(0 "F.Cu" signal "TOP")
		(4 "In1.Cu" signal "GND")
		(6 "In2.Cu" signal "VCC")
		(8 "In3.Cu" signal "VCC1")
		(10 "In4.Cu" signal "GND1")
		(12 "In5.Cu" signal "IN1")
		(14 "In6.Cu" signal "GND2")
		(16 "In7.Cu" signal "IN2")
		(18 "In8.Cu" signal "GND3")
		(20 "In9.Cu" signal "IN3")
		(22 "In10.Cu" signal "GND4")
		(24 "In11.Cu" signal "IN4")
		(26 "In12.Cu" signal "GND5")
		(28 "In13.Cu" signal "IN5")
		(30 "In14.Cu" signal "GND6")
		(32 "In15.Cu" signal "IN6")
		(34 "In16.Cu" signal "GND7")
		(2 "B.Cu" signal "BOTTOM")
		(9 "F.Adhes" user "F.Adhesive")
		(11 "B.Adhes" user "B.Adhesive")
		(13 "F.Paste" user "Package Geometry/Pastemask Top")
		(15 "B.Paste" user "Package Geometry/Pastemask Bottom")
		(5 "F.SilkS" user "Ref Des/Silkscreen Top")
		(7 "B.SilkS" user "Ref Des/Silkscreen Bottom")
		(1 "F.Mask" user "Board Geometry/Soldermask Top")
		(3 "B.Mask" user "Board Geometry/Soldermask Bottom")
		(17 "Dwgs.User" user "User.Drawings")
		(19 "Cmts.User" user "User.Comments")
		(21 "Eco1.User" user "User.Eco1")
		(23 "Eco2.User" user "User.Eco2")
		(25 "Edge.Cuts" user "Board Geometry/Outline")
		(27 "Margin" user)
		(31 "F.CrtYd" user "Package Geometry/Place Bound Top")
		(29 "B.CrtYd" user "Package Geometry/Place Bound Bottom")
		(35 "F.Fab" user "Ref Des/Assembly Top")
		(33 "B.Fab" user "Ref Des/Assembly Bottom")
	)
	(footprint ""
		(layer "F.Cu")
		(at 140.582142 -38.041072 180)
		(property "Reference" "R6061"
			(at 0 0 180)
			(layer "F.SilkS")
			(hide yes)
			(effects
				(font
					(size 1.27 1.27)
				)
			)
		)
		(property "Value" ""
			(at 0 0 180)
			(layer "F.Fab")
			(effects
				(font
					(size 1.27 1.27)
				)
			)
		)
		(duplicate_pad_numbers_are_jumpers no)
		(fp_line
			(start 0.7874 0.4064)
			(end -0.7874 0.4064)
			(stroke
				(width 0.1524)
				(type default)
			)
			(layer "F.SilkS")
		)
		(fp_line
			(start 0.7874 -0.4064)
			(end 0.7874 0.4064)
			(stroke
				(width 0.1524)
				(type default)
			)
			(layer "F.SilkS")
		)
		(fp_line
			(start -0.7874 0.4064)
			(end -0.7874 -0.4064)
			(stroke
				(width 0.1524)
				(type default)
			)
			(layer "F.SilkS")
		)
		(fp_line
			(start -0.7874 -0.4064)
			(end 0.7874 -0.4064)
			(stroke
				(width 0.1524)
				(type default)
			)
			(layer "F.SilkS")
		)
		(fp_line
			(start 0.67945 0.3048)
			(end 0.120396 0.3048)
			(stroke
				(width 0.1)
				(type default)
			)
			(layer "F.Fab")
		)
		(fp_line
			(start 0.67945 -0.3048)
			(end 0.67945 0.3048)
			(stroke
				(width 0.1)
				(type default)
			)
			(layer "F.Fab")
		)
		(fp_line
			(start 0.12065 -0.2794)
			(end 0.12065 -0.3048)
			(stroke
				(width 0.1)
				(type default)
			)
			(layer "F.Fab")
		)
		(fp_line
			(start 0.12065 -0.3048)
			(end 0.67945 -0.3048)
			(stroke
				(width 0.1)
				(type default)
			)
			(layer "F.Fab")
		)
		(fp_line
			(start 0.120396 0.3048)
			(end 0.120396 0.2794)
			(stroke
				(width 0.1)
				(type default)
			)
			(layer "F.Fab")
		)
		(fp_line
			(start 0.120396 0.2794)
			(end -0.12065 0.2794)
			(stroke
				(width 0.1)
				(type default)
			)
			(layer "F.Fab")
		)
		(fp_line
			(start -0.12065 0.3048)
			(end -0.67945 0.3048)
			(stroke
				(width 0.1)
				(type default)
			)
			(layer "F.Fab")
		)
		(fp_line
			(start -0.12065 0.2794)
			(end -0.12065 0.3048)
			(stroke
				(width 0.1)
				(type default)
			)
			(layer "F.Fab")
		)
		(fp_line
			(start -0.12065 -0.2794)
			(end 0.12065 -0.2794)
			(stroke
				(width 0.1)
				(type default)
			)
			(layer "F.Fab")
		)
		(fp_line
			(start -0.12065 -0.305054)
			(end -0.12065 -0.2794)
			(stroke
				(width 0.1)
				(type default)
			)
			(layer "F.Fab")
		)
		(fp_line
			(start -0.67945 0.3048)
			(end -0.67945 -0.305054)
			(stroke
				(width 0.1)
				(type default)
			)
			(layer "F.Fab")
		)
		(fp_line
			(start -0.67945 -0.305054)
			(end -0.12065 -0.305054)
			(stroke
				(width 0.1)
				(type default)
			)
			(layer "F.Fab")
		)
		(pad "1" smd circle
			(at -0.40005 0 180)
			(size 0 0)
			(layers "F.Cu" "F.Mask" "F.Paste")
			(net "P5V_AUX")
		)
		(pad "2" smd circle
			(at 0.40005 0 180)
			(size 0 0)
			(layers "F.Cu" "F.Mask" "F.Paste")
			(net "P3V3_SSD5_PG_G2")
		)
	)
	(footprint ""
		(layer "F.Cu")
		(at 149.414992 -20.724876)
		(property "Reference" "H110"
			(at 1.500886 -2.63398 0)
			(unlocked yes)
			(layer "B.SilkS")
			(effects
				(font
					(size 0.7874 0.5842)
					(thickness 0.1524)
				)
				(justify left mirror)
			)
		)
		(property "Value" ""
			(at 0 0 0)
			(layer "F.Fab")
			(effects
				(font
					(size 1.27 1.27)
				)
			)
		)
		(duplicate_pad_numbers_are_jumpers no)
		(pad "1" thru_hole rect
			(at 0 0)
			(size 4.2164 5.0038)
			(drill 2.0066
				(offset 0.099822 0)
			)
			(layers "*.Cu" "*.Mask")
			(remove_unused_layers no)
			(net "Net_8553")
			(clearance -0.8509)
			(padstack
				(mode front_inner_back)
				(layer "Inner"
					(shape circle)
					(size 4.0132 4.0132)
					(clearance -0.7493)
				)
				(layer "B.Cu"
					(shape circle)
					(size 4.0132 4.0132)
					(clearance -0.7493)
				)
			)
		)
	)
	(footprint ""
		(layer "F.Cu")
		(at 495.57813 -547.603172 180)
		(property "Reference" "J38_OTH"
			(at -3.2385 -1.402334 0)
			(unlocked yes)
			(layer "B.SilkS")
			(effects
				(font
					(size 0.7874 0.5842)
					(thickness 0.1524)
				)
				(justify mirror)
			)
		)
		(property "Value" ""
			(at 0 0 180)
			(layer "F.Fab")
			(effects
				(font
					(size 1.27 1.27)
				)
			)
		)
		(duplicate_pad_numbers_are_jumpers no)
		(pad "1" thru_hole circle
			(at 0 0 180)
			(size 0.4572 0.4572)
			(drill 0.2032)
			(layers "*.Cu" "*.Mask")
			(remove_unused_layers no)
			(net "Net_9098")
			(clearance 0.127)
			(thermal_gap 0.127)
			(padstack
				(mode front_inner_back)
				(layer "Inner"
					(shape circle)
					(size 0.4572 0.4572)
					(clearance 0.127)
				)
				(layer "B.Cu"
					(shape circle)
					(size 0.508 0.508)
					(clearance 0.1016)
				)
			)
		)
	)
	(footprint ""
		(layer "F.Cu")
		(at 185.89244 -31.825184 180)
		(property "Reference" "C295"
			(at 0 0 180)
			(layer "F.SilkS")
			(hide yes)
			(effects
				(font
					(size 1.27 1.27)
				)
			)
		)
		(property "Value" ""
			(at 0 0 180)
			(layer "F.Fab")
			(effects
				(font
					(size 1.27 1.27)
				)
			)
		)
		(duplicate_pad_numbers_are_jumpers no)
		(fp_line
			(start 0.299974 0.150114)
			(end -0.299974 0.150114)
			(stroke
				(width 0.1)
				(type default)
			)
			(layer "F.Fab")
		)
		(fp_line
			(start 0.299974 -0.150114)
			(end 0.299974 0.150114)
			(stroke
				(width 0.1)
				(type default)
			)
			(layer "F.Fab")
		)
		(fp_line
			(start -0.299974 0.150114)
			(end -0.299974 -0.150114)
			(stroke
				(width 0.1)
				(type default)
			)
			(layer "F.Fab")
		)
		(fp_line
			(start -0.299974 -0.150114)
			(end 0.299974 -0.150114)
			(stroke
				(width 0.1)
				(type default)
			)
			(layer "F.Fab")
		)
		(pad "1" smd rect
			(at -0.2667 0 180)
			(size 0.3048 0.381)
			(layers "F.Cu" "F.Mask" "F.Paste")
			(net "P5E_PEX1_STN2_TX_DN<38>")
		)
		(pad "2" smd rect
			(at 0.2667 0 180)
			(size 0.3048 0.381)
			(layers "F.Cu" "F.Mask" "F.Paste")
			(net "P5E_PEX1_STN2_TX_C_DN<38>")
		)
	)
	(footprint ""
		(layer "F.Cu")
		(at 133.722872 -22.867366 90)
		(property "Reference" "C3904"
			(at 0 0 90)
			(layer "F.SilkS")
			(hide yes)
			(effects
				(font
					(size 1.27 1.27)
				)
			)
		)
		(property "Value" ""
			(at 0 0 90)
			(layer "F.Fab")
			(effects
				(font
					(size 1.27 1.27)
				)
			)
		)
		(duplicate_pad_numbers_are_jumpers no)
		(fp_line
			(start 0.7874 -0.4064)
			(end 0.7874 0.4064)
			(stroke
				(width 0.1524)
				(type default)
			)
			(layer "F.SilkS")
		)
		(fp_line
			(start -0.7874 -0.4064)
			(end 0.7874 -0.4064)
			(stroke
				(width 0.1524)
				(type default)
			)
			(layer "F.SilkS")
		)
		(fp_line
			(start 0.7874 0.4064)
			(end -0.7874 0.4064)
			(stroke
				(width 0.1524)
				(type default)
			)
			(layer "F.SilkS")
		)
		(fp_line
			(start -0.7874 0.4064)
			(end -0.7874 -0.4064)
			(stroke
				(width 0.1524)
				(type default)
			)
			(layer "F.SilkS")
		)
		(fp_line
			(start -0.12065 -0.305054)
			(end -0.12065 -0.2794)
			(stroke
				(width 0.1)
				(type default)
			)
			(layer "F.Fab")
		)
		(fp_line
			(start -0.67945 -0.305054)
			(end -0.12065 -0.305054)
			(stroke
				(width 0.1)
				(type default)
			)
			(layer "F.Fab")
		)
		(fp_line
			(start 0.67945 -0.3048)
			(end 0.67945 0.3048)
			(stroke
				(width 0.1)
				(type default)
			)
			(layer "F.Fab")
		)
		(fp_line
			(start 0.12065 -0.3048)
			(end 0.67945 -0.3048)
			(stroke
				(width 0.1)
				(type default)
			)
			(layer "F.Fab")
		)
		(fp_line
			(start 0.12065 -0.2794)
			(end 0.12065 -0.3048)
			(stroke
				(width 0.1)
				(type default)
			)
			(layer "F.Fab")
		)
		(fp_line
			(start -0.12065 -0.2794)
			(end 0.12065 -0.2794)
			(stroke
				(width 0.1)
				(type default)
			)
			(layer "F.Fab")
		)
		(fp_line
			(start 0.120396 0.2794)
			(end -0.12065 0.2794)
			(stroke
				(width 0.1)
				(type default)
			)
			(layer "F.Fab")
		)
		(fp_line
			(start -0.12065 0.2794)
			(end -0.12065 0.3048)
			(stroke
				(width 0.1)
				(type default)
			)
			(layer "F.Fab")
		)
		(fp_line
			(start 0.67945 0.3048)
			(end 0.120396 0.3048)
			(stroke
				(width 0.1)
				(type default)
			)
			(layer "F.Fab")
		)
		(fp_line
			(start 0.120396 0.3048)
			(end 0.120396 0.2794)
			(stroke
				(width 0.1)
				(type default)
			)
			(layer "F.Fab")
		)
		(fp_line
			(start -0.12065 0.3048)
			(end -0.67945 0.3048)
			(stroke
				(width 0.1)
				(type default)
			)
			(layer "F.Fab")
		)
		(fp_line
			(start -0.67945 0.3048)
			(end -0.67945 -0.305054)
			(stroke
				(width 0.1)
				(type default)
			)
			(layer "F.Fab")
		)
		(pad "1" smd circle
			(at -0.40005 0 90)
			(size 0 0)
			(layers "F.Cu" "F.Mask" "F.Paste")
			(net "P12V_SSD4")
		)
		(pad "2" smd circle
			(at 0.40005 0 90)
			(size 0 0)
			(layers "F.Cu" "F.Mask" "F.Paste")
			(net "GND")
		)
	)
	(footprint ""
		(layer "F.Cu")
		(at 313.839606 -87.349076 -90)
		(property "Reference" "R300"
			(at 0 0 270)
			(layer "F.SilkS")
			(hide yes)
			(effects
				(font
					(size 1.27 1.27)
				)
			)
		)
		(property "Value" ""
			(at 0 0 270)
			(layer "F.Fab")
			(effects
				(font
					(size 1.27 1.27)
				)
			)
		)
		(duplicate_pad_numbers_are_jumpers no)
		(fp_line
			(start -0.7874 0.4064)
			(end -0.7874 -0.4064)
			(stroke
				(width 0.1524)
				(type default)
			)
			(layer "F.SilkS")
		)
		(fp_line
			(start 0.7874 0.4064)
			(end -0.7874 0.4064)
			(stroke
				(width 0.1524)
				(type default)
			)
			(layer "F.SilkS")
		)
		(fp_line
			(start -0.7874 -0.4064)
			(end 0.7874 -0.4064)
			(stroke
				(width 0.1524)
				(type default)
			)
			(layer "F.SilkS")
		)
		(fp_line
			(start 0.7874 -0.4064)
			(end 0.7874 0.4064)
			(stroke
				(width 0.1524)
				(type default)
			)
			(layer "F.SilkS")
		)
		(fp_line
			(start -0.67945 0.3048)
			(end -0.67945 -0.305054)
			(stroke
				(width 0.1)
				(type default)
			)
			(layer "F.Fab")
		)
		(fp_line
			(start -0.12065 0.3048)
			(end -0.67945 0.3048)
			(stroke
				(width 0.1)
				(type default)
			)
			(layer "F.Fab")
		)
		(fp_line
			(start 0.120396 0.3048)
			(end 0.120396 0.2794)
			(stroke
				(width 0.1)
				(type default)
			)
			(layer "F.Fab")
		)
		(fp_line
			(start 0.67945 0.3048)
			(end 0.120396 0.3048)
			(stroke
				(width 0.1)
				(type default)
			)
			(layer "F.Fab")
		)
		(fp_line
			(start -0.12065 0.2794)
			(end -0.12065 0.3048)
			(stroke
				(width 0.1)
				(type default)
			)
			(layer "F.Fab")
		)
		(fp_line
			(start 0.120396 0.2794)
			(end -0.12065 0.2794)
			(stroke
				(width 0.1)
				(type default)
			)
			(layer "F.Fab")
		)
		(fp_line
			(start -0.12065 -0.2794)
			(end 0.12065 -0.2794)
			(stroke
				(width 0.1)
				(type default)
			)
			(layer "F.Fab")
		)
		(fp_line
			(start 0.12065 -0.2794)
			(end 0.12065 -0.3048)
			(stroke
				(width 0.1)
				(type default)
			)
			(layer "F.Fab")
		)
		(fp_line
			(start 0.12065 -0.3048)
			(end 0.67945 -0.3048)
			(stroke
				(width 0.1)
				(type default)
			)
			(layer "F.Fab")
		)
		(fp_line
			(start 0.67945 -0.3048)
			(end 0.67945 0.3048)
			(stroke
				(width 0.1)
				(type default)
			)
			(layer "F.Fab")
		)
		(fp_line
			(start -0.67945 -0.305054)
			(end -0.12065 -0.305054)
			(stroke
				(width 0.1)
				(type default)
			)
			(layer "F.Fab")
		)
		(fp_line
			(start -0.12065 -0.305054)
			(end -0.12065 -0.2794)
			(stroke
				(width 0.1)
				(type default)
			)
			(layer "F.Fab")
		)
		(pad "1" smd circle
			(at -0.40005 0 270)
			(size 0 0)
			(layers "F.Cu" "F.Mask" "F.Paste")
			(net "RST_NIC5_PERST0_R_N")
		)
		(pad "2" smd circle
			(at 0.40005 0 270)
			(size 0 0)
			(layers "F.Cu" "F.Mask" "F.Paste")
			(net "RST_HP_NIC5_BUF_N")
		)
	)
	(footprint ""
		(layer "F.Cu")
		(at 263.207246 -260.639814 -90)
		(property "Reference" "C3366"
			(at 0 0 270)
			(layer "F.SilkS")
			(hide yes)
			(effects
				(font
					(size 1.27 1.27)
				)
			)
		)
		(property "Value" ""
			(at 0 0 270)
			(layer "F.Fab")
			(effects
				(font
					(size 1.27 1.27)
				)
			)
		)
		(duplicate_pad_numbers_are_jumpers no)
		(fp_line
			(start -0.299974 0.150114)
			(end -0.299974 -0.150114)
			(stroke
				(width 0.1)
				(type default)
			)
			(layer "F.Fab")
		)
		(fp_line
			(start 0.299974 0.150114)
			(end -0.299974 0.150114)
			(stroke
				(width 0.1)
				(type default)
			)
			(layer "F.Fab")
		)
		(fp_line
			(start -0.299974 -0.150114)
			(end 0.299974 -0.150114)
			(stroke
				(width 0.1)
				(type default)
			)
			(layer "F.Fab")
		)
		(fp_line
			(start 0.299974 -0.150114)
			(end 0.299974 0.150114)
			(stroke
				(width 0.1)
				(type default)
			)
			(layer "F.Fab")
		)
		(pad "1" smd rect
			(at -0.2667 0 270)
			(size 0.3048 0.381)
			(layers "F.Cu" "F.Mask" "F.Paste")
			(net "P1V8_PLL0_PEX2")
		)
		(pad "2" smd rect
			(at 0.2667 0 270)
			(size 0.3048 0.381)
			(layers "F.Cu" "F.Mask" "F.Paste")
			(net "GND")
		)
	)
	(footprint ""
		(layer "F.Cu")
		(at 3.247644 -21.317712 90)
		(property "Reference" "R5732"
			(at 0 0 90)
			(layer "F.SilkS")
			(hide yes)
			(effects
				(font
					(size 1.27 1.27)
				)
			)
		)
		(property "Value" ""
			(at 0 0 90)
			(layer "F.Fab")
			(effects
				(font
					(size 1.27 1.27)
				)
			)
		)
		(duplicate_pad_numbers_are_jumpers no)
		(fp_line
			(start 0.7874 -0.4064)
			(end 0.7874 0.4064)
			(stroke
				(width 0.1524)
				(type default)
			)
			(layer "F.SilkS")
		)
		(fp_line
			(start -0.7874 -0.4064)
			(end 0.7874 -0.4064)
			(stroke
				(width 0.1524)
				(type default)
			)
			(layer "F.SilkS")
		)
		(fp_line
			(start 0.7874 0.4064)
			(end -0.7874 0.4064)
			(stroke
				(width 0.1524)
				(type default)
			)
			(layer "F.SilkS")
		)
		(fp_line
			(start -0.7874 0.4064)
			(end -0.7874 -0.4064)
			(stroke
				(width 0.1524)
				(type default)
			)
			(layer "F.SilkS")
		)
		(fp_line
			(start -0.12065 -0.305054)
			(end -0.12065 -0.2794)
			(stroke
				(width 0.1)
				(type default)
			)
			(layer "F.Fab")
		)
		(fp_line
			(start -0.67945 -0.305054)
			(end -0.12065 -0.305054)
			(stroke
				(width 0.1)
				(type default)
			)
			(layer "F.Fab")
		)
		(fp_line
			(start 0.67945 -0.3048)
			(end 0.67945 0.3048)
			(stroke
				(width 0.1)
				(type default)
			)
			(layer "F.Fab")
		)
		(fp_line
			(start 0.12065 -0.3048)
			(end 0.67945 -0.3048)
			(stroke
				(width 0.1)
				(type default)
			)
			(layer "F.Fab")
		)
		(fp_line
			(start 0.12065 -0.2794)
			(end 0.12065 -0.3048)
			(stroke
				(width 0.1)
				(type default)
			)
			(layer "F.Fab")
		)
		(fp_line
			(start -0.12065 -0.2794)
			(end 0.12065 -0.2794)
			(stroke
				(width 0.1)
				(type default)
			)
			(layer "F.Fab")
		)
		(fp_line
			(start 0.120396 0.2794)
			(end -0.12065 0.2794)
			(stroke
				(width 0.1)
				(type default)
			)
			(layer "F.Fab")
		)
		(fp_line
			(start -0.12065 0.2794)
			(end -0.12065 0.3048)
			(stroke
				(width 0.1)
				(type default)
			)
			(layer "F.Fab")
		)
		(fp_line
			(start 0.67945 0.3048)
			(end 0.120396 0.3048)
			(stroke
				(width 0.1)
				(type default)
			)
			(layer "F.Fab")
		)
		(fp_line
			(start 0.120396 0.3048)
			(end 0.120396 0.2794)
			(stroke
				(width 0.1)
				(type default)
			)
			(layer "F.Fab")
		)
		(fp_line
			(start -0.12065 0.3048)
			(end -0.67945 0.3048)
			(stroke
				(width 0.1)
				(type default)
			)
			(layer "F.Fab")
		)
		(fp_line
			(start -0.67945 0.3048)
			(end -0.67945 -0.305054)
			(stroke
				(width 0.1)
				(type default)
			)
			(layer "F.Fab")
		)
		(pad "1" smd circle
			(at -0.40005 0 90)
			(size 0 0)
			(layers "F.Cu" "F.Mask" "F.Paste")
			(net "SSD0_LED_ISO_N")
		)
		(pad "2" smd circle
			(at 0.40005 0 90)
			(size 0 0)
			(layers "F.Cu" "F.Mask" "F.Paste")
			(net "SSD0_LED_ISO_R_N")
		)
	)
	(footprint ""
		(layer "F.Cu")
		(at 181.199028 -178.749198 -90)
		(property "Reference" "R6671"
			(at 0 0 270)
			(layer "F.SilkS")
			(hide yes)
			(effects
				(font
					(size 1.27 1.27)
				)
			)
		)
		(property "Value" ""
			(at 0 0 270)
			(layer "F.Fab")
			(effects
				(font
					(size 1.27 1.27)
				)
			)
		)
		(duplicate_pad_numbers_are_jumpers no)
		(fp_line
			(start -0.7874 0.4064)
			(end -0.7874 -0.4064)
			(stroke
				(width 0.1524)
				(type default)
			)
			(layer "F.SilkS")
		)
		(fp_line
			(start 0.7874 0.4064)
			(end -0.7874 0.4064)
			(stroke
				(width 0.1524)
				(type default)
			)
			(layer "F.SilkS")
		)
		(fp_line
			(start -0.7874 -0.4064)
			(end 0.7874 -0.4064)
			(stroke
				(width 0.1524)
				(type default)
			)
			(layer "F.SilkS")
		)
		(fp_line
			(start 0.7874 -0.4064)
			(end 0.7874 0.4064)
			(stroke
				(width 0.1524)
				(type default)
			)
			(layer "F.SilkS")
		)
		(fp_line
			(start -0.67945 0.3048)
			(end -0.67945 -0.305054)
			(stroke
				(width 0.1)
				(type default)
			)
			(layer "F.Fab")
		)
		(fp_line
			(start -0.12065 0.3048)
			(end -0.67945 0.3048)
			(stroke
				(width 0.1)
				(type default)
			)
			(layer "F.Fab")
		)
		(fp_line
			(start 0.120396 0.3048)
			(end 0.120396 0.2794)
			(stroke
				(width 0.1)
				(type default)
			)
			(layer "F.Fab")
		)
		(fp_line
			(start 0.67945 0.3048)
			(end 0.120396 0.3048)
			(stroke
				(width 0.1)
				(type default)
			)
			(layer "F.Fab")
		)
		(fp_line
			(start -0.12065 0.2794)
			(end -0.12065 0.3048)
			(stroke
				(width 0.1)
				(type default)
			)
			(layer "F.Fab")
		)
		(fp_line
			(start 0.120396 0.2794)
			(end -0.12065 0.2794)
			(stroke
				(width 0.1)
				(type default)
			)
			(layer "F.Fab")
		)
		(fp_line
			(start -0.12065 -0.2794)
			(end 0.12065 -0.2794)
			(stroke
				(width 0.1)
				(type default)
			)
			(layer "F.Fab")
		)
		(fp_line
			(start 0.12065 -0.2794)
			(end 0.12065 -0.3048)
			(stroke
				(width 0.1)
				(type default)
			)
			(layer "F.Fab")
		)
		(fp_line
			(start 0.12065 -0.3048)
			(end 0.67945 -0.3048)
			(stroke
				(width 0.1)
				(type default)
			)
			(layer "F.Fab")
		)
		(fp_line
			(start 0.67945 -0.3048)
			(end 0.67945 0.3048)
			(stroke
				(width 0.1)
				(type default)
			)
			(layer "F.Fab")
		)
		(fp_line
			(start -0.67945 -0.305054)
			(end -0.12065 -0.305054)
			(stroke
				(width 0.1)
				(type default)
			)
			(layer "F.Fab")
		)
		(fp_line
			(start -0.12065 -0.305054)
			(end -0.12065 -0.2794)
			(stroke
				(width 0.1)
				(type default)
			)
			(layer "F.Fab")
		)
		(pad "1" smd circle
			(at -0.40005 0 270)
			(size 0 0)
			(layers "F.Cu" "F.Mask" "F.Paste")
			(net "NIC2_CLK_EN_BUF_R_N")
		)
		(pad "2" smd circle
			(at 0.40005 0 270)
			(size 0 0)
			(layers "F.Cu" "F.Mask" "F.Paste")
			(net "P3V3")
		)
	)
)
